(kicad_pcb
	(version 20260206)
	(generator "pcbnew")
	(generator_version "10.0")
	(general
		(thickness 1.6)
		(legacy_teardrops no)
	)
	(paper "A4")
	(title_block
		(title "04192023_DAF0TMB3IC0_F0TG_MB_C_brd_V02_OCP.brd")
		(comment 1 "Grand Teton / footprints 6027-6032 of 8354")
	)
	(layers
		(0 "F.Cu" signal "TOP")
		(4 "In1.Cu" signal "GND")
		(6 "In2.Cu" signal "IN1")
		(8 "In3.Cu" signal "GND1")
		(10 "In4.Cu" signal "IN2")
		(12 "In5.Cu" signal "GND2")
		(14 "In6.Cu" signal "IN3")
		(16 "In7.Cu" signal "GND3")
		(18 "In8.Cu" signal "VCC")
		(20 "In9.Cu" signal "VCC1")
		(22 "In10.Cu" signal "GND4")
		(24 "In11.Cu" signal "IN4")
		(26 "In12.Cu" signal "GND5")
		(28 "In13.Cu" signal "IN5")
		(30 "In14.Cu" signal "GND6")
		(32 "In15.Cu" signal "IN6")
		(34 "In16.Cu" signal "GND7")
		(2 "B.Cu" signal "BOTTOM")
		(9 "F.Adhes" user "F.Adhesive")
		(11 "B.Adhes" user "B.Adhesive")
		(13 "F.Paste" user "Package Geometry/Pastemask Top")
		(15 "B.Paste" user "Package Geometry/Pastemask Bottom")
		(5 "F.SilkS" user "Ref Des/Silkscreen Top")
		(7 "B.SilkS" user "Ref Des/Silkscreen Bottom")
		(1 "F.Mask" user "Board Geometry/Soldermask Top")
		(3 "B.Mask" user "Board Geometry/Soldermask Bottom")
		(17 "Dwgs.User" user "User.Drawings")
		(19 "Cmts.User" user "User.Comments")
		(21 "Eco1.User" user "User.Eco1")
		(23 "Eco2.User" user "User.Eco2")
		(25 "Edge.Cuts" user "Board Geometry/Outline")
		(27 "Margin" user)
		(31 "F.CrtYd" user "Package Geometry/Place Bound Top")
		(29 "B.CrtYd" user "Package Geometry/Place Bound Bottom")
		(35 "F.Fab" user "Ref Des/Assembly Top")
		(33 "B.Fab" user "Ref Des/Assembly Bottom")
	)
	(footprint ""
		(layer "B.Cu")
		(at 104.307386 -251.781564)
		(property "Reference" "C2411"
			(at 0 0 0)
			(layer "B.SilkS")
			(hide yes)
			(effects
				(font
					(size 1.27 1.27)
				)
				(justify mirror)
			)
		)
		(property "Value" ""
			(at 0 0 0)
			(layer "B.Fab")
			(effects
				(font
					(size 1.27 1.27)
				)
				(justify mirror)
			)
		)
		(duplicate_pad_numbers_are_jumpers no)
		(fp_line
			(start -0.7874 -0.4064)
			(end -0.7874 0.4064)
			(stroke
				(width 0.1524)
				(type default)
			)
			(layer "B.SilkS")
		)
		(fp_line
			(start -0.7874 0.4064)
			(end 0.7874 0.4064)
			(stroke
				(width 0.1524)
				(type default)
			)
			(layer "B.SilkS")
		)
		(fp_line
			(start 0.7874 -0.4064)
			(end -0.7874 -0.4064)
			(stroke
				(width 0.1524)
				(type default)
			)
			(layer "B.SilkS")
		)
		(fp_line
			(start 0.7874 0.4064)
			(end 0.7874 -0.4064)
			(stroke
				(width 0.1524)
				(type default)
			)
			(layer "B.SilkS")
		)
		(fp_line
			(start -0.67945 -0.3048)
			(end -0.67945 0.3048)
			(stroke
				(width 0.1)
				(type default)
			)
			(layer "B.Fab")
		)
		(fp_line
			(start -0.67945 0.3048)
			(end -0.120396 0.3048)
			(stroke
				(width 0.1)
				(type default)
			)
			(layer "B.Fab")
		)
		(fp_line
			(start -0.12065 -0.3048)
			(end -0.67945 -0.3048)
			(stroke
				(width 0.1)
				(type default)
			)
			(layer "B.Fab")
		)
		(fp_line
			(start -0.12065 -0.2794)
			(end -0.12065 -0.3048)
			(stroke
				(width 0.1)
				(type default)
			)
			(layer "B.Fab")
		)
		(fp_line
			(start -0.120396 0.2794)
			(end 0.12065 0.2794)
			(stroke
				(width 0.1)
				(type default)
			)
			(layer "B.Fab")
		)
		(fp_line
			(start -0.120396 0.3048)
			(end -0.120396 0.2794)
			(stroke
				(width 0.1)
				(type default)
			)
			(layer "B.Fab")
		)
		(fp_line
			(start 0.12065 -0.305054)
			(end 0.12065 -0.2794)
			(stroke
				(width 0.1)
				(type default)
			)
			(layer "B.Fab")
		)
		(fp_line
			(start 0.12065 -0.2794)
			(end -0.12065 -0.2794)
			(stroke
				(width 0.1)
				(type default)
			)
			(layer "B.Fab")
		)
		(fp_line
			(start 0.12065 0.2794)
			(end 0.12065 0.3048)
			(stroke
				(width 0.1)
				(type default)
			)
			(layer "B.Fab")
		)
		(fp_line
			(start 0.12065 0.3048)
			(end 0.67945 0.3048)
			(stroke
				(width 0.1)
				(type default)
			)
			(layer "B.Fab")
		)
		(fp_line
			(start 0.67945 -0.305054)
			(end 0.12065 -0.305054)
			(stroke
				(width 0.1)
				(type default)
			)
			(layer "B.Fab")
		)
		(fp_line
			(start 0.67945 0.3048)
			(end 0.67945 -0.305054)
			(stroke
				(width 0.1)
				(type default)
			)
			(layer "B.Fab")
		)
		(pad "1" smd circle
			(at 0.40005 0 180)
			(size 0 0)
			(layers "B.Cu" "B.Mask" "B.Paste")
			(net "PVDDCR_SOC_P1")
		)
		(pad "2" smd circle
			(at -0.40005 0 180)
			(size 0 0)
			(layers "B.Cu" "B.Mask" "B.Paste")
			(net "GND")
		)
	)
	(footprint ""
		(layer "B.Cu")
		(at 60.468002 -8.319262 -90)
		(property "Reference" "R3180"
			(at 0 0 90)
			(layer "B.SilkS")
			(hide yes)
			(effects
				(font
					(size 1.27 1.27)
				)
				(justify mirror)
			)
		)
		(property "Value" ""
			(at 0 0 90)
			(layer "B.Fab")
			(effects
				(font
					(size 1.27 1.27)
				)
				(justify mirror)
			)
		)
		(duplicate_pad_numbers_are_jumpers no)
		(fp_line
			(start -0.7874 0.4064)
			(end 0.7874 0.4064)
			(stroke
				(width 0.1524)
				(type default)
			)
			(layer "B.SilkS")
		)
		(fp_line
			(start 0.7874 0.4064)
			(end 0.7874 -0.4064)
			(stroke
				(width 0.1524)
				(type default)
			)
			(layer "B.SilkS")
		)
		(fp_line
			(start -0.7874 -0.4064)
			(end -0.7874 0.4064)
			(stroke
				(width 0.1524)
				(type default)
			)
			(layer "B.SilkS")
		)
		(fp_line
			(start 0.7874 -0.4064)
			(end -0.7874 -0.4064)
			(stroke
				(width 0.1524)
				(type default)
			)
			(layer "B.SilkS")
		)
		(fp_line
			(start -0.67945 0.3048)
			(end -0.120396 0.3048)
			(stroke
				(width 0.1)
				(type default)
			)
			(layer "B.Fab")
		)
		(fp_line
			(start -0.120396 0.3048)
			(end -0.120396 0.2794)
			(stroke
				(width 0.1)
				(type default)
			)
			(layer "B.Fab")
		)
		(fp_line
			(start 0.12065 0.3048)
			(end 0.67945 0.3048)
			(stroke
				(width 0.1)
				(type default)
			)
			(layer "B.Fab")
		)
		(fp_line
			(start 0.67945 0.3048)
			(end 0.67945 -0.305054)
			(stroke
				(width 0.1)
				(type default)
			)
			(layer "B.Fab")
		)
		(fp_line
			(start -0.120396 0.2794)
			(end 0.12065 0.2794)
			(stroke
				(width 0.1)
				(type default)
			)
			(layer "B.Fab")
		)
		(fp_line
			(start 0.12065 0.2794)
			(end 0.12065 0.3048)
			(stroke
				(width 0.1)
				(type default)
			)
			(layer "B.Fab")
		)
		(fp_line
			(start -0.12065 -0.2794)
			(end -0.12065 -0.3048)
			(stroke
				(width 0.1)
				(type default)
			)
			(layer "B.Fab")
		)
		(fp_line
			(start 0.12065 -0.2794)
			(end -0.12065 -0.2794)
			(stroke
				(width 0.1)
				(type default)
			)
			(layer "B.Fab")
		)
		(fp_line
			(start -0.67945 -0.3048)
			(end -0.67945 0.3048)
			(stroke
				(width 0.1)
				(type default)
			)
			(layer "B.Fab")
		)
		(fp_line
			(start -0.12065 -0.3048)
			(end -0.67945 -0.3048)
			(stroke
				(width 0.1)
				(type default)
			)
			(layer "B.Fab")
		)
		(fp_line
			(start 0.12065 -0.305054)
			(end 0.12065 -0.2794)
			(stroke
				(width 0.1)
				(type default)
			)
			(layer "B.Fab")
		)
		(fp_line
			(start 0.67945 -0.305054)
			(end 0.12065 -0.305054)
			(stroke
				(width 0.1)
				(type default)
			)
			(layer "B.Fab")
		)
		(pad "1" smd circle
			(at 0.40005 0 90)
			(size 0 0)
			(layers "B.Cu" "B.Mask" "B.Paste")
			(net "OCP_V3_2_PRSNTA_R_N")
		)
		(pad "2" smd circle
			(at -0.40005 0 90)
			(size 0 0)
			(layers "B.Cu" "B.Mask" "B.Paste")
			(net "GND")
		)
	)
	(footprint ""
		(layer "B.Cu")
		(at 203.87818 -79.444342)
		(property "Reference" "C1826"
			(at 0 0 0)
			(layer "B.SilkS")
			(hide yes)
			(effects
				(font
					(size 1.27 1.27)
				)
				(justify mirror)
			)
		)
		(property "Value" ""
			(at 0 0 0)
			(layer "B.Fab")
			(effects
				(font
					(size 1.27 1.27)
				)
				(justify mirror)
			)
		)
		(duplicate_pad_numbers_are_jumpers no)
		(fp_line
			(start -0.7874 -0.4064)
			(end -0.7874 0.4064)
			(stroke
				(width 0.1524)
				(type default)
			)
			(layer "B.SilkS")
		)
		(fp_line
			(start -0.7874 0.4064)
			(end 0.7874 0.4064)
			(stroke
				(width 0.1524)
				(type default)
			)
			(layer "B.SilkS")
		)
		(fp_line
			(start 0.7874 -0.4064)
			(end -0.7874 -0.4064)
			(stroke
				(width 0.1524)
				(type default)
			)
			(layer "B.SilkS")
		)
		(fp_line
			(start 0.7874 0.4064)
			(end 0.7874 -0.4064)
			(stroke
				(width 0.1524)
				(type default)
			)
			(layer "B.SilkS")
		)
		(fp_line
			(start -0.67945 -0.3048)
			(end -0.67945 0.3048)
			(stroke
				(width 0.1)
				(type default)
			)
			(layer "B.Fab")
		)
		(fp_line
			(start -0.67945 0.3048)
			(end -0.120396 0.3048)
			(stroke
				(width 0.1)
				(type default)
			)
			(layer "B.Fab")
		)
		(fp_line
			(start -0.12065 -0.3048)
			(end -0.67945 -0.3048)
			(stroke
				(width 0.1)
				(type default)
			)
			(layer "B.Fab")
		)
		(fp_line
			(start -0.12065 -0.2794)
			(end -0.12065 -0.3048)
			(stroke
				(width 0.1)
				(type default)
			)
			(layer "B.Fab")
		)
		(fp_line
			(start -0.120396 0.2794)
			(end 0.12065 0.2794)
			(stroke
				(width 0.1)
				(type default)
			)
			(layer "B.Fab")
		)
		(fp_line
			(start -0.120396 0.3048)
			(end -0.120396 0.2794)
			(stroke
				(width 0.1)
				(type default)
			)
			(layer "B.Fab")
		)
		(fp_line
			(start 0.12065 -0.305054)
			(end 0.12065 -0.2794)
			(stroke
				(width 0.1)
				(type default)
			)
			(layer "B.Fab")
		)
		(fp_line
			(start 0.12065 -0.2794)
			(end -0.12065 -0.2794)
			(stroke
				(width 0.1)
				(type default)
			)
			(layer "B.Fab")
		)
		(fp_line
			(start 0.12065 0.2794)
			(end 0.12065 0.3048)
			(stroke
				(width 0.1)
				(type default)
			)
			(layer "B.Fab")
		)
		(fp_line
			(start 0.12065 0.3048)
			(end 0.67945 0.3048)
			(stroke
				(width 0.1)
				(type default)
			)
			(layer "B.Fab")
		)
		(fp_line
			(start 0.67945 -0.305054)
			(end 0.12065 -0.305054)
			(stroke
				(width 0.1)
				(type default)
			)
			(layer "B.Fab")
		)
		(fp_line
			(start 0.67945 0.3048)
			(end 0.67945 -0.305054)
			(stroke
				(width 0.1)
				(type default)
			)
			(layer "B.Fab")
		)
		(pad "1" smd circle
			(at 0.40005 0 180)
			(size 0 0)
			(layers "B.Cu" "B.Mask" "B.Paste")
			(net "P3V3_AUX")
		)
		(pad "2" smd circle
			(at -0.40005 0 180)
			(size 0 0)
			(layers "B.Cu" "B.Mask" "B.Paste")
			(net "GND")
		)
	)
	(footprint ""
		(layer "B.Cu")
		(at 311.277 -358.14 -90)
		(property "Reference" "PR32"
			(at 0 0 90)
			(layer "B.SilkS")
			(hide yes)
			(effects
				(font
					(size 1.27 1.27)
				)
				(justify mirror)
			)
		)
		(property "Value" ""
			(at 0 0 90)
			(layer "B.Fab")
			(effects
				(font
					(size 1.27 1.27)
				)
				(justify mirror)
			)
		)
		(duplicate_pad_numbers_are_jumpers no)
		(fp_line
			(start -0.7874 0.4064)
			(end 0.7874 0.4064)
			(stroke
				(width 0.1524)
				(type default)
			)
			(layer "B.SilkS")
		)
		(fp_line
			(start 0.7874 0.4064)
			(end 0.7874 -0.4064)
			(stroke
				(width 0.1524)
				(type default)
			)
			(layer "B.SilkS")
		)
		(fp_line
			(start -0.7874 -0.4064)
			(end -0.7874 0.4064)
			(stroke
				(width 0.1524)
				(type default)
			)
			(layer "B.SilkS")
		)
		(fp_line
			(start 0.7874 -0.4064)
			(end -0.7874 -0.4064)
			(stroke
				(width 0.1524)
				(type default)
			)
			(layer "B.SilkS")
		)
		(fp_line
			(start -0.67945 0.3048)
			(end -0.120396 0.3048)
			(stroke
				(width 0.1)
				(type default)
			)
			(layer "B.Fab")
		)
		(fp_line
			(start -0.120396 0.3048)
			(end -0.120396 0.2794)
			(stroke
				(width 0.1)
				(type default)
			)
			(layer "B.Fab")
		)
		(fp_line
			(start 0.12065 0.3048)
			(end 0.67945 0.3048)
			(stroke
				(width 0.1)
				(type default)
			)
			(layer "B.Fab")
		)
		(fp_line
			(start 0.67945 0.3048)
			(end 0.67945 -0.305054)
			(stroke
				(width 0.1)
				(type default)
			)
			(layer "B.Fab")
		)
		(fp_line
			(start -0.120396 0.2794)
			(end 0.12065 0.2794)
			(stroke
				(width 0.1)
				(type default)
			)
			(layer "B.Fab")
		)
		(fp_line
			(start 0.12065 0.2794)
			(end 0.12065 0.3048)
			(stroke
				(width 0.1)
				(type default)
			)
			(layer "B.Fab")
		)
		(fp_line
			(start -0.12065 -0.2794)
			(end -0.12065 -0.3048)
			(stroke
				(width 0.1)
				(type default)
			)
			(layer "B.Fab")
		)
		(fp_line
			(start 0.12065 -0.2794)
			(end -0.12065 -0.2794)
			(stroke
				(width 0.1)
				(type default)
			)
			(layer "B.Fab")
		)
		(fp_line
			(start -0.67945 -0.3048)
			(end -0.67945 0.3048)
			(stroke
				(width 0.1)
				(type default)
			)
			(layer "B.Fab")
		)
		(fp_line
			(start -0.12065 -0.3048)
			(end -0.67945 -0.3048)
			(stroke
				(width 0.1)
				(type default)
			)
			(layer "B.Fab")
		)
		(fp_line
			(start 0.12065 -0.305054)
			(end 0.12065 -0.2794)
			(stroke
				(width 0.1)
				(type default)
			)
			(layer "B.Fab")
		)
		(fp_line
			(start 0.67945 -0.305054)
			(end 0.12065 -0.305054)
			(stroke
				(width 0.1)
				(type default)
			)
			(layer "B.Fab")
		)
		(pad "1" smd circle
			(at 0.40005 0 90)
			(size 0 0)
			(layers "B.Cu" "B.Mask" "B.Paste")
			(net "NC_PVDDCR_CPU1_P0_IMON8")
		)
		(pad "2" smd circle
			(at -0.40005 0 90)
			(size 0 0)
			(layers "B.Cu" "B.Mask" "B.Paste")
			(net "GND")
		)
	)
	(footprint ""
		(layer "B.Cu")
		(at 20.480782 -411.707584 180)
		(property "Reference" "PR6820"
			(at 0 0 0)
			(layer "B.SilkS")
			(hide yes)
			(effects
				(font
					(size 1.27 1.27)
				)
				(justify mirror)
			)
		)
		(property "Value" ""
			(at 0 0 0)
			(layer "B.Fab")
			(effects
				(font
					(size 1.27 1.27)
				)
				(justify mirror)
			)
		)
		(duplicate_pad_numbers_are_jumpers no)
		(fp_line
			(start 0.7874 0.4064)
			(end 0.7874 -0.4064)
			(stroke
				(width 0.1524)
				(type default)
			)
			(layer "B.SilkS")
		)
		(fp_line
			(start 0.7874 -0.4064)
			(end -0.7874 -0.4064)
			(stroke
				(width 0.1524)
				(type default)
			)
			(layer "B.SilkS")
		)
		(fp_line
			(start -0.7874 0.4064)
			(end 0.7874 0.4064)
			(stroke
				(width 0.1524)
				(type default)
			)
			(layer "B.SilkS")
		)
		(fp_line
			(start -0.7874 -0.4064)
			(end -0.7874 0.4064)
			(stroke
				(width 0.1524)
				(type default)
			)
			(layer "B.SilkS")
		)
		(fp_line
			(start 0.67945 0.3048)
			(end 0.67945 -0.305054)
			(stroke
				(width 0.1)
				(type default)
			)
			(layer "B.Fab")
		)
		(fp_line
			(start 0.67945 -0.305054)
			(end 0.12065 -0.305054)
			(stroke
				(width 0.1)
				(type default)
			)
			(layer "B.Fab")
		)
		(fp_line
			(start 0.12065 0.3048)
			(end 0.67945 0.3048)
			(stroke
				(width 0.1)
				(type default)
			)
			(layer "B.Fab")
		)
		(fp_line
			(start 0.12065 0.2794)
			(end 0.12065 0.3048)
			(stroke
				(width 0.1)
				(type default)
			)
			(layer "B.Fab")
		)
		(fp_line
			(start 0.12065 -0.2794)
			(end -0.12065 -0.2794)
			(stroke
				(width 0.1)
				(type default)
			)
			(layer "B.Fab")
		)
		(fp_line
			(start 0.12065 -0.305054)
			(end 0.12065 -0.2794)
			(stroke
				(width 0.1)
				(type default)
			)
			(layer "B.Fab")
		)
		(fp_line
			(start -0.120396 0.3048)
			(end -0.120396 0.2794)
			(stroke
				(width 0.1)
				(type default)
			)
			(layer "B.Fab")
		)
		(fp_line
			(start -0.120396 0.2794)
			(end 0.12065 0.2794)
			(stroke
				(width 0.1)
				(type default)
			)
			(layer "B.Fab")
		)
		(fp_line
			(start -0.12065 -0.2794)
			(end -0.12065 -0.3048)
			(stroke
				(width 0.1)
				(type default)
			)
			(layer "B.Fab")
		)
		(fp_line
			(start -0.12065 -0.3048)
			(end -0.67945 -0.3048)
			(stroke
				(width 0.1)
				(type default)
			)
			(layer "B.Fab")
		)
		(fp_line
			(start -0.67945 0.3048)
			(end -0.120396 0.3048)
			(stroke
				(width 0.1)
				(type default)
			)
			(layer "B.Fab")
		)
		(fp_line
			(start -0.67945 -0.3048)
			(end -0.67945 0.3048)
			(stroke
				(width 0.1)
				(type default)
			)
			(layer "B.Fab")
		)
		(pad "1" smd circle
			(at 0.40005 0)
			(size 0 0)
			(layers "B.Cu" "B.Mask" "B.Paste")
			(net "P0V9_RETIMER_CPU1_SVID_SDA")
		)
		(pad "2" smd circle
			(at -0.40005 0)
			(size 0 0)
			(layers "B.Cu" "B.Mask" "B.Paste")
			(net "GND")
		)
	)
	(footprint ""
		(layer "B.Cu")
		(at 99.273106 -390.560052 90)
		(property "Reference" "C351"
			(at 0 0 90)
			(layer "B.SilkS")
			(hide yes)
			(effects
				(font
					(size 1.27 1.27)
				)
				(justify mirror)
			)
		)
		(property "Value" ""
			(at 0 0 90)
			(layer "B.Fab")
			(effects
				(font
					(size 1.27 1.27)
				)
				(justify mirror)
			)
		)
		(duplicate_pad_numbers_are_jumpers no)
		(fp_line
			(start 0.7874 -0.4064)
			(end -0.7874 -0.4064)
			(stroke
				(width 0.1524)
				(type default)
			)
			(layer "B.SilkS")
		)
		(fp_line
			(start -0.7874 -0.4064)
			(end -0.7874 0.4064)
			(stroke
				(width 0.1524)
				(type default)
			)
			(layer "B.SilkS")
		)
		(fp_line
			(start 0.7874 0.4064)
			(end 0.7874 -0.4064)
			(stroke
				(width 0.1524)
				(type default)
			)
			(layer "B.SilkS")
		)
		(fp_line
			(start -0.7874 0.4064)
			(end 0.7874 0.4064)
			(stroke
				(width 0.1524)
				(type default)
			)
			(layer "B.SilkS")
		)
		(fp_line
			(start 0.67945 -0.305054)
			(end 0.12065 -0.305054)
			(stroke
				(width 0.1)
				(type default)
			)
			(layer "B.Fab")
		)
		(fp_line
			(start 0.12065 -0.305054)
			(end 0.12065 -0.2794)
			(stroke
				(width 0.1)
				(type default)
			)
			(layer "B.Fab")
		)
		(fp_line
			(start -0.12065 -0.3048)
			(end -0.67945 -0.3048)
			(stroke
				(width 0.1)
				(type default)
			)
			(layer "B.Fab")
		)
		(fp_line
			(start -0.67945 -0.3048)
			(end -0.67945 0.3048)
			(stroke
				(width 0.1)
				(type default)
			)
			(layer "B.Fab")
		)
		(fp_line
			(start 0.12065 -0.2794)
			(end -0.12065 -0.2794)
			(stroke
				(width 0.1)
				(type default)
			)
			(layer "B.Fab")
		)
		(fp_line
			(start -0.12065 -0.2794)
			(end -0.12065 -0.3048)
			(stroke
				(width 0.1)
				(type default)
			)
			(layer "B.Fab")
		)
		(fp_line
			(start 0.12065 0.2794)
			(end 0.12065 0.3048)
			(stroke
				(width 0.1)
				(type default)
			)
			(layer "B.Fab")
		)
		(fp_line
			(start -0.120396 0.2794)
			(end 0.12065 0.2794)
			(stroke
				(width 0.1)
				(type default)
			)
			(layer "B.Fab")
		)
		(fp_line
			(start 0.67945 0.3048)
			(end 0.67945 -0.305054)
			(stroke
				(width 0.1)
				(type default)
			)
			(layer "B.Fab")
		)
		(fp_line
			(start 0.12065 0.3048)
			(end 0.67945 0.3048)
			(stroke
				(width 0.1)
				(type default)
			)
			(layer "B.Fab")
		)
		(fp_line
			(start -0.120396 0.3048)
			(end -0.120396 0.2794)
			(stroke
				(width 0.1)
				(type default)
			)
			(layer "B.Fab")
		)
		(fp_line
			(start -0.67945 0.3048)
			(end -0.120396 0.3048)
			(stroke
				(width 0.1)
				(type default)
			)
			(layer "B.Fab")
		)
		(pad "1" smd circle
			(at 0.40005 0 270)
			(size 0 0)
			(layers "B.Cu" "B.Mask" "B.Paste")
			(net "P0V9_CPU1_RT1_2A")
		)
		(pad "2" smd circle
			(at -0.40005 0 270)
			(size 0 0)
			(layers "B.Cu" "B.Mask" "B.Paste")
			(net "GND")
		)
	)
)
